# TIMECARD (Time Appliance Project (Time Card)) — schematic netlist excerpt (pin names and nets, part order shuffled) for the footprints in the layout excerpt that follows; sources: Cadence DE-HDL packaged netlist, KiCad conversion of R4006-B0001-02_R01.brd

R3  RESISTOR  4.7KOHM 1%  pkg SMC_0402R_H016  page 16 : \1\ = XP3R3V_FPGA ; \2\ = SEC_EEPROM_WP
R316  RESISTOR  0OHM -  pkg SMC_0402R_H016  page 19 : \1\ = ICP10100_I2C_SDA ; \2\ = BF_ICP10100_I2C_SDA

(kicad_pcb
	(version 20260206)
	(generator "pcbnew")
	(generator_version "10.0")
	(general
		(thickness 1.6)
		(legacy_teardrops no)
	)
	(paper "A4")
	(title_block
		(title "timecard-production-celestica-r4006 — R4006-B0001-02_R01.brd")
		(comment 1 "Time Appliance Project (Time Card) / footprints 736-737 of 1113")
	)
	(layers
		(0 "F.Cu" signal "TOP")
		(4 "In1.Cu" signal "L02_GND1")
		(6 "In2.Cu" signal "L03_SIG1")
		(8 "In3.Cu" signal "L04_GND2")
		(10 "In4.Cu" signal "L05_VCC1")
		(12 "In5.Cu" signal "L06_VCC2")
		(14 "In6.Cu" signal "L07_GND3")
		(16 "In7.Cu" signal "L08_SIG2")
		(18 "In8.Cu" signal "L09_GND4")
		(2 "B.Cu" signal "BOTTOM")
		(9 "F.Adhes" user "F.Adhesive")
		(11 "B.Adhes" user "B.Adhesive")
		(13 "F.Paste" user "Package Geometry/Pastemask Top")
		(15 "B.Paste" user "Package Geometry/Pastemask Bottom")
		(5 "F.SilkS" user "Ref Des/Silkscreen Top")
		(7 "B.SilkS" user "Ref Des/Silkscreen Bottom")
		(1 "F.Mask" user "Board Geometry/Soldermask Top")
		(3 "B.Mask" user "Board Geometry/Soldermask Bottom")
		(17 "Dwgs.User" user "User.Drawings")
		(19 "Cmts.User" user "User.Comments")
		(21 "Eco1.User" user "User.Eco1")
		(23 "Eco2.User" user "User.Eco2")
		(25 "Edge.Cuts" user "Board Geometry/Outline")
		(27 "Margin" user)
		(31 "F.CrtYd" user "Package Geometry/Place Bound Top")
		(29 "B.CrtYd" user "Package Geometry/Place Bound Bottom")
		(35 "F.Fab" user "Ref Des/Assembly Top")
		(33 "B.Fab" user "Ref Des/Assembly Bottom")
	)
	(footprint ""
		(layer "B.Cu")
		(at 20.447 -61.5442 90)
		(property "Reference" "R316"
			(at -0.3302 -3.97637 270)
			(unlocked yes)
			(layer "B.SilkS")
			(effects
				(font
					(size 0.7874 0.5842)
					(thickness 0.1524)
				)
				(justify mirror)
			)
		)
		(property "Value" "VAL*"
			(at -0.02032 2.13233 90)
			(unlocked yes)
			(layer "B.Fab")
			(hide yes)
			(effects
				(font
					(size 0.7874 0.5842)
					(thickness 0.1524)
				)
				(justify mirror)
			)
		)
		(property "Tolerance" "TOL*"
			(at -0.044704 3.05435 90)
			(unlocked yes)
			(layer "Cmts.User")
			(hide yes)
			(effects
				(font
					(size 0.7874 0.5842)
					(thickness 0.1524)
				)
				(justify mirror)
			)
		)
		(property "User Part Number" "PARTNUM*"
			(at -0.02032 4.024884 90)
			(unlocked yes)
			(layer "Cmts.User")
			(hide yes)
			(effects
				(font
					(size 0.7874 0.5842)
					(thickness 0.1524)
				)
				(justify mirror)
			)
		)
		(property "Device Type" "RESISTOR-G155-100R0-J0,0OHM,-"
			(at -0.008382 1.210564 90)
			(unlocked yes)
			(layer "B.Fab")
			(hide yes)
			(effects
				(font
					(size 0.7874 0.5842)
					(thickness 0.1524)
				)
				(justify mirror)
			)
		)
		(duplicate_pad_numbers_are_jumpers no)
		(fp_line
			(start 1.143 -0.5588)
			(end 1.143 0.5588)
			(stroke
				(width 0.1)
				(type default)
			)
			(layer "B.SilkS")
		)
		(fp_line
			(start -1.143 -0.5588)
			(end 1.143 -0.5588)
			(stroke
				(width 0.1)
				(type default)
			)
			(layer "B.SilkS")
		)
		(fp_line
			(start 1.143 0.5588)
			(end -1.143 0.5588)
			(stroke
				(width 0.1)
				(type default)
			)
			(layer "B.SilkS")
		)
		(fp_line
			(start -1.143 0.5588)
			(end -1.143 -0.5588)
			(stroke
				(width 0.1)
				(type default)
			)
			(layer "B.SilkS")
		)
		(fp_poly
			(pts
				(xy 1.143 0.5588) (xy -1.143 0.5588) (xy -1.143 -0.5588) (xy 1.143 -0.5588)
			)
			(stroke
				(width 0)
				(type default)
			)
			(fill no)
			(layer "B.CrtYd")
		)
		(fp_line
			(start 0.508 -0.3048)
			(end 0.508 0.3048)
			(stroke
				(width 0.1)
				(type default)
			)
			(layer "B.Fab")
		)
		(fp_line
			(start -0.508 -0.3048)
			(end 0.508 -0.3048)
			(stroke
				(width 0.1)
				(type default)
			)
			(layer "B.Fab")
		)
		(fp_line
			(start 0.508 0.3048)
			(end -0.508 0.3048)
			(stroke
				(width 0.1)
				(type default)
			)
			(layer "B.Fab")
		)
		(fp_line
			(start -0.508 0.3048)
			(end -0.508 -0.3048)
			(stroke
				(width 0.1)
				(type default)
			)
			(layer "B.Fab")
		)
		(pad "1" smd rect
			(at 0.5334 0 270)
			(size 0.7112 0.6096)
			(layers "B.Cu" "B.Mask" "B.Paste")
			(net "ICP10100_I2C_SDA")
		)
		(pad "2" smd rect
			(at -0.5334 0 270)
			(size 0.7112 0.6096)
			(layers "B.Cu" "B.Mask" "B.Paste")
			(net "BF_ICP10100_I2C_SDA")
		)
		(zone
			(layer "B.Cu")
			(hatch none 0.5)
			(connect_pads
				(clearance 0)
			)
			(min_thickness 0.25)
			(keepout
				(tracks not_allowed)
				(vias allowed)
				(pads allowed)
				(copperpour not_allowed)
				(footprints allowed)
			)
			(placement
				(enabled no)
				(sheetname "")
			)
			(fill
				(thermal_gap 0.5)
				(thermal_bridge_width 0.5)
				(island_removal_mode 0)
			)
			(polygon
				(pts
					(xy 20.7518 -61.6204) (xy 20.1422 -61.6204) (xy 20.1422 -61.468) (xy 20.7518 -61.468)
				)
			)
		)
		(zone
			(layer "B.Cu")
			(hatch none 0.5)
			(connect_pads
				(clearance 0)
			)
			(min_thickness 0.25)
			(keepout
				(tracks allowed)
				(vias not_allowed)
				(pads allowed)
				(copperpour not_allowed)
				(footprints allowed)
			)
			(placement
				(enabled no)
				(sheetname "")
			)
			(fill
				(thermal_gap 0.5)
				(thermal_bridge_width 0.5)
				(island_removal_mode 0)
			)
			(polygon
				(pts
					(xy 20.7518 -61.6204) (xy 20.1422 -61.6204) (xy 20.1422 -61.468) (xy 20.7518 -61.468)
				)
			)
		)
	)
	(footprint ""
		(layer "B.Cu")
		(at 21.082 -16.891)
		(property "Reference" "R3"
			(at 0.381 1.69037 0)
			(unlocked yes)
			(layer "B.SilkS")
			(effects
				(font
					(size 0.7874 0.5842)
					(thickness 0.1524)
				)
				(justify mirror)
			)
		)
		(property "Value" "VAL*"
			(at -0.02032 2.13233 0)
			(unlocked yes)
			(layer "B.Fab")
			(hide yes)
			(effects
				(font
					(size 0.7874 0.5842)
					(thickness 0.1524)
				)
				(justify mirror)
			)
		)
		(property "Device Type" "RESISTOR-G155-14701-01,4.7KOHMA"
			(at -0.008382 1.210564 0)
			(unlocked yes)
			(layer "B.Fab")
			(hide yes)
			(effects
				(font
					(size 0.7874 0.5842)
					(thickness 0.1524)
				)
				(justify mirror)
			)
		)
		(property "User Part Number" "PARTNUM*"
			(at -0.02032 4.024884 0)
			(unlocked yes)
			(layer "Cmts.User")
			(hide yes)
			(effects
				(font
					(size 0.7874 0.5842)
					(thickness 0.1524)
				)
				(justify mirror)
			)
		)
		(property "Tolerance" "TOL*"
			(at -0.044704 3.05435 0)
			(unlocked yes)
			(layer "Cmts.User")
			(hide yes)
			(effects
				(font
					(size 0.7874 0.5842)
					(thickness 0.1524)
				)
				(justify mirror)
			)
		)
		(duplicate_pad_numbers_are_jumpers no)
		(fp_line
			(start -1.143 -0.5588)
			(end 1.143 -0.5588)
			(stroke
				(width 0.1)
				(type default)
			)
			(layer "B.SilkS")
		)
		(fp_line
			(start -1.143 0.5588)
			(end -1.143 -0.5588)
			(stroke
				(width 0.1)
				(type default)
			)
			(layer "B.SilkS")
		)
		(fp_line
			(start 1.143 -0.5588)
			(end 1.143 0.5588)
			(stroke
				(width 0.1)
				(type default)
			)
			(layer "B.SilkS")
		)
		(fp_line
			(start 1.143 0.5588)
			(end -1.143 0.5588)
			(stroke
				(width 0.1)
				(type default)
			)
			(layer "B.SilkS")
		)
		(fp_rect
			(start -1.143 -0.5588)
			(end 1.143 0.5588)
			(stroke
				(width 0)
				(type default)
			)
			(fill no)
			(layer "B.CrtYd")
		)
		(fp_line
			(start -0.508 -0.3048)
			(end 0.508 -0.3048)
			(stroke
				(width 0.1)
				(type default)
			)
			(layer "B.Fab")
		)
		(fp_line
			(start -0.508 0.3048)
			(end -0.508 -0.3048)
			(stroke
				(width 0.1)
				(type default)
			)
			(layer "B.Fab")
		)
		(fp_line
			(start 0.508 -0.3048)
			(end 0.508 0.3048)
			(stroke
				(width 0.1)
				(type default)
			)
			(layer "B.Fab")
		)
		(fp_line
			(start 0.508 0.3048)
			(end -0.508 0.3048)
			(stroke
				(width 0.1)
				(type default)
			)
			(layer "B.Fab")
		)
		(pad "1" smd rect
			(at 0.5334 0 180)
			(size 0.7112 0.6096)
			(layers "B.Cu" "B.Mask" "B.Paste")
			(net "XP3R3V_FPGA")
		)
		(pad "2" smd rect
			(at -0.5334 0 180)
			(size 0.7112 0.6096)
			(layers "B.Cu" "B.Mask" "B.Paste")
			(net "SEC_EEPROM_WP")
		)
		(zone
			(layer "B.Cu")
			(hatch none 0.5)
			(connect_pads
				(clearance 0)
			)
			(min_thickness 0.25)
			(keepout
				(tracks allowed)
				(vias not_allowed)
				(pads allowed)
				(copperpour not_allowed)
				(footprints allowed)
			)
			(placement
				(enabled no)
				(sheetname "")
			)
			(fill
				(thermal_gap 0.5)
				(thermal_bridge_width 0.5)
				(island_removal_mode 0)
			)
			(polygon
				(pts
					(xy 21.0058 -17.1958) (xy 21.0058 -16.5862) (xy 21.1582 -16.5862) (xy 21.1582 -17.1958)
				)
			)
		)
	)
)
